# T6G (Grand Teton) — schematic netlist excerpt (pin names and nets, part order shuffled) for the footprints in the layout excerpt that follows; sources: Cadence DE-HDL packaged netlist, KiCad conversion of 04192023_DAF0TMB3IC0_F0TG_MB_C_brd_V02_OCP.brd

PR91  Q_RES  0 5% CHIP  pkg 0402LF  page 202 : A = PVDDCR_CPU1_P0_VOS4 ; B = PVDDCR_CPU1_P0
C640  Q_CAP  0.1UF 25V 10% X7R  pkg 0402  page 132 : A = P3V3_AUX ; B = GND

(kicad_pcb
	(version 20260206)
	(generator "pcbnew")
	(generator_version "10.0")
	(general
		(thickness 1.6)
		(legacy_teardrops no)
	)
	(paper "A4")
	(title_block
		(title "04192023_DAF0TMB3IC0_F0TG_MB_C_brd_V02_OCP.brd")
		(comment 1 "Grand Teton / footprints 5199-5200 of 8354")
	)
	(layers
		(0 "F.Cu" signal "TOP")
		(4 "In1.Cu" signal "GND")
		(6 "In2.Cu" signal "IN1")
		(8 "In3.Cu" signal "GND1")
		(10 "In4.Cu" signal "IN2")
		(12 "In5.Cu" signal "GND2")
		(14 "In6.Cu" signal "IN3")
		(16 "In7.Cu" signal "GND3")
		(18 "In8.Cu" signal "VCC")
		(20 "In9.Cu" signal "VCC1")
		(22 "In10.Cu" signal "GND4")
		(24 "In11.Cu" signal "IN4")
		(26 "In12.Cu" signal "GND5")
		(28 "In13.Cu" signal "IN5")
		(30 "In14.Cu" signal "GND6")
		(32 "In15.Cu" signal "IN6")
		(34 "In16.Cu" signal "GND7")
		(2 "B.Cu" signal "BOTTOM")
		(9 "F.Adhes" user "F.Adhesive")
		(11 "B.Adhes" user "B.Adhesive")
		(13 "F.Paste" user "Package Geometry/Pastemask Top")
		(15 "B.Paste" user "Package Geometry/Pastemask Bottom")
		(5 "F.SilkS" user "Ref Des/Silkscreen Top")
		(7 "B.SilkS" user "Ref Des/Silkscreen Bottom")
		(1 "F.Mask" user "Board Geometry/Soldermask Top")
		(3 "B.Mask" user "Board Geometry/Soldermask Bottom")
		(17 "Dwgs.User" user "User.Drawings")
		(19 "Cmts.User" user "User.Comments")
		(21 "Eco1.User" user "User.Eco1")
		(23 "Eco2.User" user "User.Eco2")
		(25 "Edge.Cuts" user "Board Geometry/Outline")
		(27 "Margin" user)
		(31 "F.CrtYd" user "Package Geometry/Place Bound Top")
		(29 "B.CrtYd" user "Package Geometry/Place Bound Bottom")
		(35 "F.Fab" user "Ref Des/Assembly Top")
		(33 "B.Fab" user "Ref Des/Assembly Bottom")
	)
	(footprint ""
		(layer "B.Cu")
		(at 305.034696 -349.381572 -90)
		(property "Reference" "PR91"
			(at 0 0 90)
			(layer "B.SilkS")
			(hide yes)
			(effects
				(font
					(size 1.27 1.27)
				)
				(justify mirror)
			)
		)
		(property "Value" ""
			(at 0 0 90)
			(layer "B.Fab")
			(effects
				(font
					(size 1.27 1.27)
				)
				(justify mirror)
			)
		)
		(duplicate_pad_numbers_are_jumpers no)
		(fp_line
			(start -0.7874 0.4064)
			(end 0.7874 0.4064)
			(stroke
				(width 0.1524)
				(type default)
			)
			(layer "B.SilkS")
		)
		(fp_line
			(start 0.7874 0.4064)
			(end 0.7874 -0.4064)
			(stroke
				(width 0.1524)
				(type default)
			)
			(layer "B.SilkS")
		)
		(fp_line
			(start -0.7874 -0.4064)
			(end -0.7874 0.4064)
			(stroke
				(width 0.1524)
				(type default)
			)
			(layer "B.SilkS")
		)
		(fp_line
			(start 0.7874 -0.4064)
			(end -0.7874 -0.4064)
			(stroke
				(width 0.1524)
				(type default)
			)
			(layer "B.SilkS")
		)
		(fp_line
			(start -0.67945 0.3048)
			(end -0.120396 0.3048)
			(stroke
				(width 0.1)
				(type default)
			)
			(layer "B.Fab")
		)
		(fp_line
			(start -0.120396 0.3048)
			(end -0.120396 0.2794)
			(stroke
				(width 0.1)
				(type default)
			)
			(layer "B.Fab")
		)
		(fp_line
			(start 0.12065 0.3048)
			(end 0.67945 0.3048)
			(stroke
				(width 0.1)
				(type default)
			)
			(layer "B.Fab")
		)
		(fp_line
			(start 0.67945 0.3048)
			(end 0.67945 -0.305054)
			(stroke
				(width 0.1)
				(type default)
			)
			(layer "B.Fab")
		)
		(fp_line
			(start -0.120396 0.2794)
			(end 0.12065 0.2794)
			(stroke
				(width 0.1)
				(type default)
			)
			(layer "B.Fab")
		)
		(fp_line
			(start 0.12065 0.2794)
			(end 0.12065 0.3048)
			(stroke
				(width 0.1)
				(type default)
			)
			(layer "B.Fab")
		)
		(fp_line
			(start -0.12065 -0.2794)
			(end -0.12065 -0.3048)
			(stroke
				(width 0.1)
				(type default)
			)
			(layer "B.Fab")
		)
		(fp_line
			(start 0.12065 -0.2794)
			(end -0.12065 -0.2794)
			(stroke
				(width 0.1)
				(type default)
			)
			(layer "B.Fab")
		)
		(fp_line
			(start -0.67945 -0.3048)
			(end -0.67945 0.3048)
			(stroke
				(width 0.1)
				(type default)
			)
			(layer "B.Fab")
		)
		(fp_line
			(start -0.12065 -0.3048)
			(end -0.67945 -0.3048)
			(stroke
				(width 0.1)
				(type default)
			)
			(layer "B.Fab")
		)
		(fp_line
			(start 0.12065 -0.305054)
			(end 0.12065 -0.2794)
			(stroke
				(width 0.1)
				(type default)
			)
			(layer "B.Fab")
		)
		(fp_line
			(start 0.67945 -0.305054)
			(end 0.12065 -0.305054)
			(stroke
				(width 0.1)
				(type default)
			)
			(layer "B.Fab")
		)
		(pad "1" smd circle
			(at 0.40005 0 90)
			(size 0 0)
			(layers "B.Cu" "B.Mask" "B.Paste")
			(net "PVDDCR_CPU1_P0_VOS4")
		)
		(pad "2" smd circle
			(at -0.40005 0 90)
			(size 0 0)
			(layers "B.Cu" "B.Mask" "B.Paste")
			(net "PVDDCR_CPU1_P0")
		)
	)
	(footprint ""
		(layer "B.Cu")
		(at 192.287652 -80.20304 -90)
		(property "Reference" "C640"
			(at 0 0 90)
			(layer "B.SilkS")
			(hide yes)
			(effects
				(font
					(size 1.27 1.27)
				)
				(justify mirror)
			)
		)
		(property "Value" ""
			(at 0 0 90)
			(layer "B.Fab")
			(effects
				(font
					(size 1.27 1.27)
				)
				(justify mirror)
			)
		)
		(duplicate_pad_numbers_are_jumpers no)
		(fp_line
			(start -0.7874 0.4064)
			(end 0.7874 0.4064)
			(stroke
				(width 0.1524)
				(type default)
			)
			(layer "B.SilkS")
		)
		(fp_line
			(start 0.7874 0.4064)
			(end 0.7874 -0.4064)
			(stroke
				(width 0.1524)
				(type default)
			)
			(layer "B.SilkS")
		)
		(fp_line
			(start -0.7874 -0.4064)
			(end -0.7874 0.4064)
			(stroke
				(width 0.1524)
				(type default)
			)
			(layer "B.SilkS")
		)
		(fp_line
			(start 0.7874 -0.4064)
			(end -0.7874 -0.4064)
			(stroke
				(width 0.1524)
				(type default)
			)
			(layer "B.SilkS")
		)
		(fp_line
			(start -0.67945 0.3048)
			(end -0.120396 0.3048)
			(stroke
				(width 0.1)
				(type default)
			)
			(layer "B.Fab")
		)
		(fp_line
			(start -0.120396 0.3048)
			(end -0.120396 0.2794)
			(stroke
				(width 0.1)
				(type default)
			)
			(layer "B.Fab")
		)
		(fp_line
			(start 0.12065 0.3048)
			(end 0.67945 0.3048)
			(stroke
				(width 0.1)
				(type default)
			)
			(layer "B.Fab")
		)
		(fp_line
			(start 0.67945 0.3048)
			(end 0.67945 -0.305054)
			(stroke
				(width 0.1)
				(type default)
			)
			(layer "B.Fab")
		)
		(fp_line
			(start -0.120396 0.2794)
			(end 0.12065 0.2794)
			(stroke
				(width 0.1)
				(type default)
			)
			(layer "B.Fab")
		)
		(fp_line
			(start 0.12065 0.2794)
			(end 0.12065 0.3048)
			(stroke
				(width 0.1)
				(type default)
			)
			(layer "B.Fab")
		)
		(fp_line
			(start -0.12065 -0.2794)
			(end -0.12065 -0.3048)
			(stroke
				(width 0.1)
				(type default)
			)
			(layer "B.Fab")
		)
		(fp_line
			(start 0.12065 -0.2794)
			(end -0.12065 -0.2794)
			(stroke
				(width 0.1)
				(type default)
			)
			(layer "B.Fab")
		)
		(fp_line
			(start -0.67945 -0.3048)
			(end -0.67945 0.3048)
			(stroke
				(width 0.1)
				(type default)
			)
			(layer "B.Fab")
		)
		(fp_line
			(start -0.12065 -0.3048)
			(end -0.67945 -0.3048)
			(stroke
				(width 0.1)
				(type default)
			)
			(layer "B.Fab")
		)
		(fp_line
			(start 0.12065 -0.305054)
			(end 0.12065 -0.2794)
			(stroke
				(width 0.1)
				(type default)
			)
			(layer "B.Fab")
		)
		(fp_line
			(start 0.67945 -0.305054)
			(end 0.12065 -0.305054)
			(stroke
				(width 0.1)
				(type default)
			)
			(layer "B.Fab")
		)
		(pad "1" smd circle
			(at 0.40005 0 90)
			(size 0 0)
			(layers "B.Cu" "B.Mask" "B.Paste")
			(net "P3V3_AUX")
		)
		(pad "2" smd circle
			(at -0.40005 0 90)
			(size 0 0)
			(layers "B.Cu" "B.Mask" "B.Paste")
			(net "GND")
		)
	)
)
